(kicad_pcb
	(version 20241229)
	(generator "pcbnew")
	(generator_version "9.0")
	(general
		(thickness 1.6)
		(legacy_teardrops no)
	)
	(paper "A4")
	(title_block
		(title "environment-sensor")
		(comment 1 "footprints 106-108 of 109")
	)
	(layers
		(0 "F.Cu" signal)
		(4 "In1.Cu" signal)
		(6 "In2.Cu" signal)
		(2 "B.Cu" signal)
		(9 "F.Adhes" user "F.Adhesive")
		(11 "B.Adhes" user "B.Adhesive")
		(13 "F.Paste" user)
		(15 "B.Paste" user)
		(5 "F.SilkS" user "F.Silkscreen")
		(7 "B.SilkS" user "B.Silkscreen")
		(1 "F.Mask" user)
		(3 "B.Mask" user)
		(17 "Dwgs.User" user "User.Drawings")
		(19 "Cmts.User" user "User.Comments")
		(21 "Eco1.User" user "User.Eco1")
		(23 "Eco2.User" user "User.Eco2")
		(25 "Edge.Cuts" user)
		(27 "Margin" user)
		(31 "F.CrtYd" user "F.Courtyard")
		(29 "B.CrtYd" user "B.Courtyard")
		(35 "F.Fab" user)
		(33 "B.Fab" user)
	)
	(footprint "antmicro-footprints:oshw-logo"
		(layer "B.Cu")
		(at 206.621 129.967 180)
		(descr "OSHW Logo")
		(tags "OSHW Logo")
		(property "Reference" "N2"
			(at 0 4.4 0)
			(layer "B.SilkS")
			(hide yes)
			(effects
				(font
					(size 0.7 0.7)
					(thickness 0.15)
				)
				(justify left bottom mirror)
			)
		)
		(property "Value" "oshw_logo"
			(at 0 3.4 0)
			(layer "B.Fab")
			(hide yes)
			(effects
				(font
					(size 0.7 0.7)
					(thickness 0.15)
				)
				(justify left bottom mirror)
			)
		)
		(property "Description" "Mechanical part"
			(at 0 0 180)
			(layer "F.Fab")
			(hide yes)
			(effects
				(font
					(size 1.27 1.27)
					(thickness 0.15)
				)
			)
		)
		(property "Author" "Antmicro"
			(at 413.242 259.934 0)
			(layer "B.Fab")
			(hide yes)
			(effects
				(font
					(size 1 1)
					(thickness 0.15)
				)
				(justify mirror)
			)
		)
		(property "License" "Apache-2.0"
			(at 413.242 259.934 0)
			(layer "B.Fab")
			(hide yes)
			(effects
				(font
					(size 1 1)
					(thickness 0.15)
				)
				(justify mirror)
			)
		)
		(property "MPN" ""
			(at 413.242 259.934 0)
			(layer "B.Fab")
			(hide yes)
			(effects
				(font
					(size 1 1)
					(thickness 0.15)
				)
				(justify mirror)
			)
		)
		(property "Manufacturer" ""
			(at 413.242 259.934 0)
			(layer "B.Fab")
			(hide yes)
			(effects
				(font
					(size 1 1)
					(thickness 0.15)
				)
				(justify mirror)
			)
		)
		(property "Public" "False"
			(at 413.242 259.934 0)
			(layer "B.Fab")
			(hide yes)
			(effects
				(font
					(size 1 1)
					(thickness 0.15)
				)
				(justify mirror)
			)
		)
		(sheetfile "environment-sensor.kicad_sch")
		(attr exclude_from_pos_files exclude_from_bom allow_soldermask_bridges)
	)
	(footprint "antmicro-footprints:Conn_JST_SH_1x4_SM04B-SRSS-TB-LF-SN"
		(layer "B.Cu")
		(at 207.2 117.6 -90)
		(property "Reference" "J3"
			(at 0 3.7 90)
			(layer "B.SilkS")
			(effects
				(font
					(size 0.7 0.7)
					(thickness 0.15)
				)
				(justify left bottom mirror)
			)
		)
		(property "Value" "JST_SH_1x4_SM04B-SRSS-TB-LF-SN"
			(at 0 -3.9 90)
			(layer "B.Fab")
			(effects
				(font
					(size 0.7 0.7)
					(thickness 0.15)
				)
				(justify left bottom mirror)
			)
		)
		(property "Description" "Pin Header, Right Angle, Wire-to-Board, 1 mm, 1 Rows, 4 Contacts, Surface Mount Right Angle, SH"
			(at 0 0 270)
			(layer "F.Fab")
			(hide yes)
			(effects
				(font
					(size 1.27 1.27)
					(thickness 0.15)
				)
			)
		)
		(property "Author" "Antmicro"
			(at 89.6 324.8 0)
			(layer "B.Fab")
			(hide yes)
			(effects
				(font
					(size 1 1)
					(thickness 0.15)
				)
				(justify mirror)
			)
		)
		(property "License" "Apache-2.0"
			(at 89.6 324.8 0)
			(layer "B.Fab")
			(hide yes)
			(effects
				(font
					(size 1 1)
					(thickness 0.15)
				)
				(justify mirror)
			)
		)
		(property "MPN" "SM04B-SRSS-TB(LF)(SN)"
			(at 89.6 324.8 0)
			(layer "B.Fab")
			(hide yes)
			(effects
				(font
					(size 1 1)
					(thickness 0.15)
				)
				(justify mirror)
			)
		)
		(property "Manufacturer" "JST Automotive Connectors"
			(at 89.6 324.8 0)
			(layer "B.Fab")
			(hide yes)
			(effects
				(font
					(size 1 1)
					(thickness 0.15)
				)
				(justify mirror)
			)
		)
		(sheetfile "environment-sensor.kicad_sch")
		(attr smd)
		(fp_line
			(start -3.2 2)
			(end -3.2 -0.6)
			(stroke
				(width 0.15)
				(type solid)
			)
			(layer "B.SilkS")
		)
		(fp_line
			(start -2 2)
			(end -3.2 2)
			(stroke
				(width 0.15)
				(type solid)
			)
			(layer "B.SilkS")
		)
		(fp_line
			(start 2 2)
			(end 3.2 2)
			(stroke
				(width 0.15)
				(type solid)
			)
			(layer "B.SilkS")
		)
		(fp_line
			(start 3.2 2)
			(end 3.2 -0.6)
			(stroke
				(width 0.15)
				(type solid)
			)
			(layer "B.SilkS")
		)
		(fp_line
			(start -2 -2.6)
			(end 2 -2.6)
			(stroke
				(width 0.15)
				(type solid)
			)
			(layer "B.SilkS")
		)
		(fp_circle
			(center -2.1 2.5)
			(end -2.05 2.5)
			(stroke
				(width 0.15)
				(type solid)
			)
			(fill yes)
			(layer "B.SilkS")
		)
		(fp_rect
			(start -3.65 3.14)
			(end 3.65 -2.9)
			(stroke
				(width 0.05)
				(type solid)
			)
			(fill no)
			(layer "B.CrtYd")
		)
		(fp_rect
			(start -3 2.475)
			(end 3 -2.475)
			(stroke
				(width 0.15)
				(type solid)
			)
			(fill no)
			(layer "B.Fab")
		)
		(pad "1" smd roundrect
			(at -1.5 2.12 90)
			(size 0.6 1.55)
			(layers "B.Cu" "B.Mask" "B.Paste")
			(roundrect_rratio 0.25)
			(net 1 "GND")
			(pintype "passive")
		)
		(pad "2" smd roundrect
			(at -0.5 2.12 90)
			(size 0.6 1.55)
			(layers "B.Cu" "B.Mask" "B.Paste")
			(roundrect_rratio 0.25)
			(net 2 "+3V3")
			(pintype "passive")
		)
		(pad "3" smd roundrect
			(at 0.5 2.12 90)
			(size 0.6 1.55)
			(layers "B.Cu" "B.Mask" "B.Paste")
			(roundrect_rratio 0.25)
			(net 9 "I2C_1_SDA")
			(pintype "passive")
		)
		(pad "4" smd roundrect
			(at 1.5 2.12 90)
			(size 0.6 1.55)
			(layers "B.Cu" "B.Mask" "B.Paste")
			(roundrect_rratio 0.25)
			(net 8 "I2C_1_SCL")
			(pintype "passive")
		)
		(pad "MP" smd roundrect
			(at -2.8 -1.755 270)
			(size 1.2 1.8)
			(layers "B.Cu" "B.Mask" "B.Paste")
			(roundrect_rratio 0.25)
			(net 89 "unconnected-(J3-PadMP)")
			(pintype "passive+no_connect")
		)
		(pad "MP" smd roundrect
			(at 2.8 -1.755 270)
			(size 1.2 1.8)
			(layers "B.Cu" "B.Mask" "B.Paste")
			(roundrect_rratio 0.25)
			(net 89 "unconnected-(J3-PadMP)")
			(pintype "passive+no_connect")
		)
	)
	(footprint "antmicro-footprints:BAT_BAT-HLD-012-SMT-TR"
		(layer "B.Cu")
		(at 176.4 133 180)
		(descr "Linx Technologies Battery Holder, CR1216/1225, Surface Mount, from SnapEDA: https://www.snapeda.com/parts/BAT-HLD-012-SMT-TR/Linx/view-part/?ref=search&t=BAT-HLD-012-SMT-TR")
		(tags "battery holder retainer cr1216 cr1225 smt lithium ")
		(property "Reference" "BAT1"
			(at 6.8 -5.8 180)
			(layer "B.SilkS")
			(effects
				(font
					(size 0.65 0.65)
					(thickness 0.15)
				)
				(justify mirror)
			)
		)
		(property "Value" "BAT-HLD-012-SMT-TR"
			(at 12.858 -6.589 0)
			(layer "B.Fab")
			(effects
				(font
					(size 1.4 1.4)
					(thickness 0.15)
				)
				(justify mirror)
			)
		)
		(property "Description" "BATTERY HOLDER, CR1216/1225, SMT"
			(at 0 0 180)
			(layer "F.Fab")
			(hide yes)
			(effects
				(font
					(size 1.27 1.27)
					(thickness 0.15)
				)
			)
		)
		(property "Author" "Antmicro"
			(at 352.8 266 0)
			(layer "B.Fab")
			(hide yes)
			(effects
				(font
					(size 1 1)
					(thickness 0.15)
				)
				(justify mirror)
			)
		)
		(property "License" "Apache-2.0"
			(at 352.8 266 0)
			(layer "B.Fab")
			(hide yes)
			(effects
				(font
					(size 1 1)
					(thickness 0.15)
				)
				(justify mirror)
			)
		)
		(property "MPN" "BAT-HLD-012-SMT-TR"
			(at 352.8 266 0)
			(layer "B.Fab")
			(hide yes)
			(effects
				(font
					(size 1 1)
					(thickness 0.15)
				)
				(justify mirror)
			)
		)
		(property "Manufacturer" "Linx Technologies"
			(at 352.8 266 0)
			(layer "B.Fab")
			(hide yes)
			(effects
				(font
					(size 1 1)
					(thickness 0.15)
				)
				(justify mirror)
			)
		)
		(sheetfile "environment-sensor.kicad_sch")
		(attr smd)
		(fp_line
			(start 6.749 4.55)
			(end 6.749 2.92)
			(stroke
				(width 0.15)
				(type solid)
			)
			(layer "B.SilkS")
		)
		(fp_line
			(start 6.749 -4.95)
			(end 6.749 -2.818)
			(stroke
				(width 0.15)
				(type solid)
			)
			(layer "B.SilkS")
		)
		(fp_line
			(start 5.499 -4.95)
			(end 6.749 -4.95)
			(stroke
				(width 0.15)
				(type solid)
			)
			(layer "B.SilkS")
		)
		(fp_line
			(start 3.249 4.55)
			(end 6.749 4.55)
			(stroke
				(width 0.15)
				(type solid)
			)
			(layer "B.SilkS")
		)
		(fp_line
			(start -6.75 4.55)
			(end -3.25 4.55)
			(stroke
				(width 0.15)
				(type solid)
			)
			(layer "B.SilkS")
		)
		(fp_line
			(start -6.75 2.92)
			(end -6.75 4.55)
			(stroke
				(width 0.15)
				(type solid)
			)
			(layer "B.SilkS")
		)
		(fp_line
			(start -6.75 -2.818)
			(end -6.75 -4.95)
			(stroke
				(width 0.15)
				(type solid)
			)
			(layer "B.SilkS")
		)
		(fp_line
			(start -6.75 -4.95)
			(end -5.5 -4.95)
			(stroke
				(width 0.15)
				(type solid)
			)
			(layer "B.SilkS")
		)
		(fp_rect
			(start -9.17 5.549)
			(end 9.168 -5.548)
			(stroke
				(width 0.05)
				(type solid)
			)
			(fill no)
			(layer "B.CrtYd")
		)
		(fp_line
			(start 6.749 4.55)
			(end 6.749 -4.95)
			(stroke
				(width 0.15)
				(type solid)
			)
			(layer "B.Fab")
		)
		(fp_line
			(start 6.749 -4.95)
			(end 5.499 -4.95)
			(stroke
				(width 0.15)
				(type solid)
			)
			(layer "B.Fab")
		)
		(fp_line
			(start -5.25 4.55)
			(end 6.749 4.55)
			(stroke
				(width 0.15)
				(type solid)
			)
			(layer "B.Fab")
		)
		(fp_line
			(start -5.5 -4.95)
			(end -6.75 -4.95)
			(stroke
				(width 0.15)
				(type solid)
			)
			(layer "B.Fab")
		)
		(fp_line
			(start -6.75 2.9)
			(end -5.25 4.55)
			(stroke
				(width 0.15)
				(type solid)
			)
			(layer "B.Fab")
		)
		(fp_line
			(start -6.75 -4.95)
			(end -6.75 2.9)
			(stroke
				(width 0.15)
				(type solid)
			)
			(layer "B.Fab")
		)
		(fp_arc
			(start 5.499 -4.95)
			(mid 2.917754 -3.500268)
			(end 0 -2.999)
			(stroke
				(width 0.15)
				(type solid)
			)
			(layer "B.Fab")
		)
		(fp_arc
			(start 0 -2.999)
			(mid -2.918394 -3.499785)
			(end -5.5 -4.95)
			(stroke
				(width 0.15)
				(type solid)
			)
			(layer "B.Fab")
		)
		(pad "N" smd circle
			(at 0 0 180)
			(size 10.2 10.2)
			(layers "B.Cu" "B.Mask")
			(net 1 "GND")
			(pintype "power_out")
		)
		(pad "P1" smd rect
			(at -7.651 0.052 180)
			(size 2.5 5.1)
			(layers "B.Cu" "B.Mask" "B.Paste")
			(net 28 "Net-(U3-VBAT)")
			(pintype "power_out")
		)
		(pad "P2" smd rect
			(at 7.65 0.052 180)
			(size 2.5 5.1)
			(layers "B.Cu" "B.Mask" "B.Paste")
			(net 28 "Net-(U3-VBAT)")
			(pintype "passive")
		)
	)
)
